# BASEBOARD_FAB2 (Tioga Pass) — schematic netlist excerpt (pin names and nets, part order shuffled) for the footprints in the layout excerpt that follows; sources: Cadence DE-HDL packaged netlist, KiCad conversion of Wiwynn_Tioga_Pass_MB.brd

C25W52  CAP  1.0UF 16V 10% X6S  pkg 0402  page 149 : A = P1V2_AUX_BMC ; B = GND
R2T32  RES  0.0 5% CHIP  pkg 0402  page 93 : A = H_CPU0_ERR1_G_N ; B = H_CPU_ERR1_GTL_R_N
C2P4  CAP_A  0.1UF 16V 10% X7R  pkg 0402V  page 192 : A = P3V3_STBY ; B = GND

(kicad_pcb
	(version 20260206)
	(generator "pcbnew")
	(generator_version "10.0")
	(general
		(thickness 1.6)
		(legacy_teardrops no)
	)
	(paper "A4")
	(title_block
		(title "Wiwynn_Tioga_Pass_MB.brd")
		(comment 1 "Tioga Pass / footprints 2758-2760 of 4770")
	)
	(layers
		(0 "F.Cu" signal "TOP")
		(4 "In1.Cu" signal "L2GND")
		(6 "In2.Cu" signal "L3")
		(8 "In3.Cu" signal "L4GND")
		(10 "In4.Cu" signal "L5")
		(12 "In5.Cu" signal "L6GND")
		(14 "In6.Cu" signal "L7VCC")
		(16 "In7.Cu" signal "L8VCC")
		(18 "In8.Cu" signal "L9GND")
		(20 "In9.Cu" signal "L10")
		(22 "In10.Cu" signal "L11GND")
		(24 "In11.Cu" signal "L12")
		(26 "In12.Cu" signal "L13GND")
		(2 "B.Cu" signal "BOTTOM")
		(9 "F.Adhes" user "F.Adhesive")
		(11 "B.Adhes" user "B.Adhesive")
		(13 "F.Paste" user "Package Geometry/Pastemask Top")
		(15 "B.Paste" user "Package Geometry/Pastemask Bottom")
		(5 "F.SilkS" user "Ref Des/Silkscreen Top")
		(7 "B.SilkS" user "Ref Des/Silkscreen Bottom")
		(1 "F.Mask" user "Board Geometry/Soldermask Top")
		(3 "B.Mask" user "Board Geometry/Soldermask Bottom")
		(17 "Dwgs.User" user "User.Drawings")
		(19 "Cmts.User" user "User.Comments")
		(21 "Eco1.User" user "User.Eco1")
		(23 "Eco2.User" user "User.Eco2")
		(25 "Edge.Cuts" user "Board Geometry/Outline")
		(27 "Margin" user)
		(31 "F.CrtYd" user "Package Geometry/Place Bound Top")
		(29 "B.CrtYd" user "Package Geometry/Place Bound Bottom")
		(35 "F.Fab" user "Ref Des/Assembly Top")
		(33 "B.Fab" user "Ref Des/Assembly Bottom")
	)
	(footprint ""
		(layer "B.Cu")
		(at 375.408952 -43.224958)
		(property "Reference" "R2T32"
			(at 0 0 0)
			(layer "B.SilkS")
			(hide yes)
			(effects
				(font
					(size 1.27 1.27)
				)
				(justify mirror)
			)
		)
		(property "Value" ""
			(at 0 0 0)
			(layer "B.Fab")
			(effects
				(font
					(size 1.27 1.27)
				)
				(justify mirror)
			)
		)
		(duplicate_pad_numbers_are_jumpers no)
		(fp_poly
			(pts
				(xy 0.2794 -0.1016) (xy -0.2794 -0.1016) (xy -0.2794 0.9906) (xy 0.2794 0.9906)
			)
			(stroke
				(width 0)
				(type default)
			)
			(fill no)
			(layer "B.CrtYd")
		)
		(fp_line
			(start -0.2794 -0.1016)
			(end 0.2794 -0.1016)
			(stroke
				(width 0.1)
				(type default)
			)
			(layer "B.Fab")
		)
		(fp_line
			(start -0.2794 0.9906)
			(end -0.2794 -0.1016)
			(stroke
				(width 0.1)
				(type default)
			)
			(layer "B.Fab")
		)
		(fp_line
			(start 0.2794 -0.1016)
			(end 0.2794 0.9906)
			(stroke
				(width 0.1)
				(type default)
			)
			(layer "B.Fab")
		)
		(fp_line
			(start 0.2794 0.9906)
			(end -0.2794 0.9906)
			(stroke
				(width 0.1)
				(type default)
			)
			(layer "B.Fab")
		)
		(pad "1" smd rect
			(at 0 0 180)
			(size 0.508 0.508)
			(layers "B.Cu" "B.Mask" "B.Paste")
			(net "H_CPU0_ERR1_G_N")
		)
		(pad "2" smd rect
			(at 0 0.889 180)
			(size 0.508 0.508)
			(layers "B.Cu" "B.Mask" "B.Paste")
			(net "H_CPU_ERR1_GTL_R_N")
		)
		(zone
			(layer "B.Cu")
			(hatch none 0.5)
			(connect_pads
				(clearance 0)
			)
			(min_thickness 0.25)
			(keepout
				(tracks allowed)
				(vias not_allowed)
				(pads allowed)
				(copperpour not_allowed)
				(footprints allowed)
			)
			(placement
				(enabled no)
				(sheetname "")
			)
			(fill
				(thermal_gap 0.5)
				(thermal_bridge_width 0.5)
				(island_removal_mode 0)
			)
			(polygon
				(pts
					(xy 375.662952 -42.970958) (xy 375.154952 -42.970958) (xy 375.154952 -42.589958) (xy 375.662952 -42.589958)
				)
			)
		)
		(zone
			(layer "B.Cu")
			(hatch none 0.5)
			(connect_pads
				(clearance 0)
			)
			(min_thickness 0.25)
			(keepout
				(tracks not_allowed)
				(vias allowed)
				(pads allowed)
				(copperpour not_allowed)
				(footprints allowed)
			)
			(placement
				(enabled no)
				(sheetname "")
			)
			(fill
				(thermal_gap 0.5)
				(thermal_bridge_width 0.5)
				(island_removal_mode 0)
			)
			(polygon
				(pts
					(xy 375.662952 -42.589958) (xy 375.154952 -42.589958) (xy 375.154952 -42.970958) (xy 375.662952 -42.970958)
				)
			)
		)
	)
	(footprint ""
		(layer "B.Cu")
		(at 371.54485 -72.29348)
		(property "Reference" "C2P4"
			(at 0 0 0)
			(layer "B.SilkS")
			(hide yes)
			(effects
				(font
					(size 1.27 1.27)
				)
				(justify mirror)
			)
		)
		(property "Value" ""
			(at 0 0 0)
			(layer "B.Fab")
			(effects
				(font
					(size 1.27 1.27)
				)
				(justify mirror)
			)
		)
		(duplicate_pad_numbers_are_jumpers no)
		(fp_rect
			(start 0.2794 0.9144)
			(end -0.2794 -0.1143)
			(stroke
				(width 0)
				(type default)
			)
			(fill no)
			(layer "B.CrtYd")
		)
		(fp_line
			(start -0.2794 -0.1143)
			(end -0.2794 0.9144)
			(stroke
				(width 0.1)
				(type default)
			)
			(layer "B.Fab")
		)
		(fp_line
			(start -0.2794 0.9144)
			(end 0.2794 0.9144)
			(stroke
				(width 0.1)
				(type default)
			)
			(layer "B.Fab")
		)
		(fp_line
			(start 0.2794 -0.1143)
			(end -0.2794 -0.1143)
			(stroke
				(width 0.1)
				(type default)
			)
			(layer "B.Fab")
		)
		(fp_line
			(start 0.2794 0.9144)
			(end 0.2794 -0.1143)
			(stroke
				(width 0.1)
				(type default)
			)
			(layer "B.Fab")
		)
		(pad "1" smd custom
			(at 0 0 270)
			(size 0.10414 0.10414)
			(layers "B.Cu" "B.Mask" "B.Paste")
			(net "P3V3_STBY")
			(options
				(clearance outline)
				(anchor circle)
			)
			(primitives
				(gr_poly
					(pts
						(xy -0.20828 -0.08636) (xy -0.20828 0.08636) (xy -0.08636 0.20828) (xy 0.086614 0.20828) (xy 0.20828 0.086614)
						(xy 0.20828 -0.08636) (xy 0.08636 -0.20828) (xy -0.08636 -0.20828)
					)
					(width 0)
					(fill yes)
				)
			)
		)
		(pad "2" smd custom
			(at 0 0.8001 270)
			(size 0.10414 0.10414)
			(layers "B.Cu" "B.Mask" "B.Paste")
			(net "GND")
			(options
				(clearance outline)
				(anchor circle)
			)
			(primitives
				(gr_poly
					(pts
						(xy -0.20828 -0.08636) (xy -0.20828 0.08636) (xy -0.08636 0.20828) (xy 0.086614 0.20828) (xy 0.20828 0.086614)
						(xy 0.20828 -0.08636) (xy 0.08636 -0.20828) (xy -0.08636 -0.20828)
					)
					(width 0)
					(fill yes)
				)
			)
		)
		(zone
			(layer "B.Cu")
			(hatch none 0.5)
			(connect_pads
				(clearance 0)
			)
			(min_thickness 0.25)
			(keepout
				(tracks not_allowed)
				(vias allowed)
				(pads allowed)
				(copperpour not_allowed)
				(footprints allowed)
			)
			(placement
				(enabled no)
				(sheetname "")
			)
			(fill
				(thermal_gap 0.5)
				(thermal_bridge_width 0.5)
				(island_removal_mode 0)
			)
			(polygon
				(pts
					(xy 371.63248 -72.08393) (xy 371.63248 -71.70293) (xy 371.45722 -71.70293) (xy 371.456966 -72.08393)
				)
			)
		)
		(zone
			(layer "B.Cu")
			(hatch none 0.5)
			(connect_pads
				(clearance 0)
			)
			(min_thickness 0.25)
			(keepout
				(tracks allowed)
				(vias not_allowed)
				(pads allowed)
				(copperpour not_allowed)
				(footprints allowed)
			)
			(placement
				(enabled no)
				(sheetname "")
			)
			(fill
				(thermal_gap 0.5)
				(thermal_bridge_width 0.5)
				(island_removal_mode 0)
			)
			(polygon
				(pts
					(xy 371.63248 -72.08393) (xy 371.63248 -71.70293) (xy 371.45722 -71.70293) (xy 371.456966 -72.08393)
				)
			)
		)
	)
	(footprint ""
		(layer "B.Cu")
		(at 418.871654 -36.7665 -90)
		(property "Reference" "C25W52"
			(at 0.8382 -0.67818 270)
			(unlocked yes)
			(layer "B.SilkS")
			(effects
				(font
					(size 0.4064 0.254)
					(thickness 0.1524)
				)
				(justify left mirror)
			)
		)
		(property "Value" ""
			(at 0 0 90)
			(layer "B.Fab")
			(effects
				(font
					(size 1.27 1.27)
				)
				(justify mirror)
			)
		)
		(duplicate_pad_numbers_are_jumpers no)
		(fp_poly
			(pts
				(xy -0.3048 -0.1016) (xy -0.3048 0.9906) (xy 0.3048 0.9906) (xy 0.3048 -0.1016)
			)
			(stroke
				(width 0)
				(type default)
			)
			(fill no)
			(layer "B.CrtYd")
		)
		(fp_line
			(start -0.3048 0.9906)
			(end -0.3048 -0.1016)
			(stroke
				(width 0.1)
				(type default)
			)
			(layer "B.Fab")
		)
		(fp_line
			(start 0.3048 0.9906)
			(end -0.3048 0.9906)
			(stroke
				(width 0.1)
				(type default)
			)
			(layer "B.Fab")
		)
		(fp_line
			(start -0.3048 -0.1016)
			(end 0.3048 -0.1016)
			(stroke
				(width 0.1)
				(type default)
			)
			(layer "B.Fab")
		)
		(fp_line
			(start 0.3048 -0.1016)
			(end 0.3048 0.9906)
			(stroke
				(width 0.1)
				(type default)
			)
			(layer "B.Fab")
		)
		(pad "1" smd rect
			(at 0 0 90)
			(size 0.508 0.508)
			(layers "B.Cu" "B.Mask" "B.Paste")
			(net "P1V2_AUX_BMC")
		)
		(pad "2" smd rect
			(at 0 0.889 90)
			(size 0.508 0.508)
			(layers "B.Cu" "B.Mask" "B.Paste")
			(net "GND")
		)
		(zone
			(layer "B.Cu")
			(hatch none 0.5)
			(connect_pads
				(clearance 0)
			)
			(min_thickness 0.25)
			(keepout
				(tracks not_allowed)
				(vias allowed)
				(pads allowed)
				(copperpour not_allowed)
				(footprints allowed)
			)
			(placement
				(enabled no)
				(sheetname "")
			)
			(fill
				(thermal_gap 0.5)
				(thermal_bridge_width 0.5)
				(island_removal_mode 0)
			)
			(polygon
				(pts
					(xy 418.236654 -36.5125) (xy 418.236654 -37.0205) (xy 418.617654 -37.0205) (xy 418.617654 -36.5125)
				)
			)
		)
		(zone
			(layer "B.Cu")
			(hatch none 0.5)
			(connect_pads
				(clearance 0)
			)
			(min_thickness 0.25)
			(keepout
				(tracks allowed)
				(vias not_allowed)
				(pads allowed)
				(copperpour not_allowed)
				(footprints allowed)
			)
			(placement
				(enabled no)
				(sheetname "")
			)
			(fill
				(thermal_gap 0.5)
				(thermal_bridge_width 0.5)
				(island_removal_mode 0)
			)
			(polygon
				(pts
					(xy 418.617654 -36.5125) (xy 418.617654 -37.0205) (xy 418.236654 -37.0205) (xy 418.236654 -36.5125)
				)
			)
		)
	)
)
